FILE_TYPE = MACRO_DRAWING;
SET COLOR_WIRE YELLOW;
SET COLOR_PROP MONO;
SET COLOR_DOT WHITE;
SET COLOR_ARC YELLOW;
SET COLOR_BODY GREEN;
SET COLOR_NOTE MONO;
SET PROP_DISPLAY VALUE;
SET PAGE_NUMBER P249;
FORCEADD OFFPAGE..1
(-7700 2150);
FORCEPROP 2 LAST $XR0 146 
J 0
(-7952 2150);
DISPLAY 0.638298 (-7952 2150);
PAINT MONO (-7952 2150);
FORCEPROP 2 LAST CDS_LIB mstr_standard
J 0
(-7700 2150);
PAINT MONO (-7700 2150);
DISPLAY INVISIBLE (-7700 2150);
FORCEPROP 1 LAST COMMENT_BODY TRUE
J 0
(-7575 2050);
DISPLAY 0.872340 (-7575 2050);
PAINT GREEN (-7575 2050);
DISPLAY INVISIBLE (-7575 2050);
FORCEPROP 1 LAST OFFPAGE TRUE
J 0
(-7375 2025);
DISPLAY 0.872340 (-7375 2025);
PAINT GREEN (-7375 2025);
DISPLAY INVISIBLE (-7375 2025);
FORCEPROP 2 LAST PATH I1
J 0
(-7650 2225);
DISPLAY 1.021277 (-7650 2225);
PAINT ORANGE (-7650 2225);
DISPLAY INVISIBLE (-7650 2225);
FORCEADD GND..1
(-3200 3600);
FORCEPROP 3 LASTPIN (-3200 3650) SIG_NAME GND\g
J 0
(-3190 3660);
DISPLAY 0.659574 (-3190 3660);
PAINT MONO (-3190 3660);
DISPLAY INVISIBLE (-3190 3660);
FORCEPROP 1 LAST PATH I10
J 0
(-3125 3600);
DISPLAY 0.872340 (-3125 3600);
PAINT AQUA (-3125 3600);
DISPLAY INVISIBLE (-3125 3600);
FORCEPROP 1 LAST VOLTAGE 0.0V
J 0
(-3245 3557);
DISPLAY 0.340426 (-3245 3557);
PAINT GREEN (-3245 3557);
DISPLAY INVISIBLE (-3245 3557);
FORCEPROP 1 LAST BODY_TYPE PLUMBING
J 0
(-3245 3557);
DISPLAY 0.340426 (-3245 3557);
PAINT GREEN (-3245 3557);
DISPLAY INVISIBLE (-3245 3557);
FORCEPROP 2 LAST CDS_LIB mstr_symbols
J 0
(-3200 3600);
PAINT MONO (-3200 3600);
DISPLAY INVISIBLE (-3200 3600);
FORCEPROP 1 LAST SIZE 1B
J 0
(-3125 3550);
DISPLAY 0.872340 (-3125 3550);
PAINT AQUA (-3125 3550);
DISPLAY INVISIBLE (-3125 3550);
FORCEPROP 1 LAST HDL_POWER GND
J 0
(-3200 3750);
DISPLAY 0.872340 (-3200 3750);
PAINT GREEN (-3200 3750);
DISPLAY INVISIBLE (-3200 3750);
FORCEADD GND..1
(-4850 1675);
FORCEPROP 3 LASTPIN (-4850 1725) SIG_NAME GND\g
J 0
(-4840 1735);
DISPLAY 0.659574 (-4840 1735);
PAINT MONO (-4840 1735);
DISPLAY INVISIBLE (-4840 1735);
FORCEPROP 2 LAST CDS_LIB mstr_symbols
J 0
(-4850 1675);
PAINT MONO (-4850 1675);
DISPLAY INVISIBLE (-4850 1675);
FORCEPROP 1 LAST HDL_POWER GND
J 0
(-4850 1825);
DISPLAY 0.872340 (-4850 1825);
PAINT GREEN (-4850 1825);
DISPLAY INVISIBLE (-4850 1825);
FORCEPROP 1 LAST SIZE 1B
J 0
(-4775 1625);
DISPLAY 0.872340 (-4775 1625);
PAINT AQUA (-4775 1625);
DISPLAY INVISIBLE (-4775 1625);
FORCEPROP 1 LAST BODY_TYPE PLUMBING
J 0
(-4895 1632);
DISPLAY 0.340426 (-4895 1632);
PAINT GREEN (-4895 1632);
DISPLAY INVISIBLE (-4895 1632);
FORCEPROP 1 LAST VOLTAGE 0.0V
J 0
(-4895 1632);
DISPLAY 0.340426 (-4895 1632);
PAINT GREEN (-4895 1632);
DISPLAY INVISIBLE (-4895 1632);
FORCEPROP 1 LAST PATH I11
J 0
(-4775 1675);
DISPLAY 0.872340 (-4775 1675);
PAINT AQUA (-4775 1675);
DISPLAY INVISIBLE (-4775 1675);
FORCEADD GND..1
(-2350 2150);
FORCEPROP 3 LASTPIN (-2350 2200) SIG_NAME GND\g
J 0
(-2340 2210);
DISPLAY 0.659574 (-2340 2210);
PAINT MONO (-2340 2210);
DISPLAY INVISIBLE (-2340 2210);
FORCEPROP 1 LAST PATH I14
J 0
(-2275 2150);
DISPLAY 0.872340 (-2275 2150);
PAINT AQUA (-2275 2150);
DISPLAY INVISIBLE (-2275 2150);
FORCEPROP 1 LAST VOLTAGE 0.0V
J 0
(-2395 2107);
DISPLAY 0.340426 (-2395 2107);
PAINT GREEN (-2395 2107);
DISPLAY INVISIBLE (-2395 2107);
FORCEPROP 1 LAST BODY_TYPE PLUMBING
J 0
(-2395 2107);
DISPLAY 0.340426 (-2395 2107);
PAINT GREEN (-2395 2107);
DISPLAY INVISIBLE (-2395 2107);
FORCEPROP 2 LAST CDS_LIB mstr_symbols
J 0
(-2350 2150);
PAINT MONO (-2350 2150);
DISPLAY INVISIBLE (-2350 2150);
FORCEPROP 1 LAST SIZE 1B
J 0
(-2275 2100);
DISPLAY 0.872340 (-2275 2100);
PAINT AQUA (-2275 2100);
DISPLAY INVISIBLE (-2275 2100);
FORCEPROP 1 LAST HDL_POWER GND
J 0
(-2350 2300);
DISPLAY 0.872340 (-2350 2300);
PAINT GREEN (-2350 2300);
DISPLAY INVISIBLE (-2350 2300);
FORCEADD LMV331IDCKRG4-GP..1
(-2300 2550);
FORCEPROP 1 LAST VALUE LMV331IDCKRG4-GP
J 0
(-2225 2415);
DISPLAY 0.617021 (-2225 2415);
PAINT GREEN (-2225 2415);
FORCEPROP 1 LAST LOCATION Q9W4
J 0
(-2225 2660);
DISPLAY 0.617021 (-2225 2660);
PAINT GREEN (-2225 2660);
FORCEPROP 1 LAST CDS_LMAN_SYM_OUTLINE -100,100,100,-100
J 0
(-2300 2550);
DISPLAY 0.468085 (-2300 2550);
PAINT GREEN (-2300 2550);
DISPLAY INVISIBLE (-2300 2550);
FORCEPROP 2 LAST CDS_LIB w_hdl
J 0
(-2300 2550);
PAINT MONO (-2300 2550);
DISPLAY INVISIBLE (-2300 2550);
FORCEPROP 1 LAST PART_NUMBER 74.00331.A2F
J 0
(-2300 2550);
DISPLAY 0.617021 (-2300 2550);
PAINT GREEN (-2300 2550);
DISPLAY INVISIBLE (-2300 2550);
FORCEPROP 1 LAST PACK_TYPE DISCRET-G
J 0
(-2300 2550);
DISPLAY 0.617021 (-2300 2550);
PAINT GREEN (-2300 2550);
DISPLAY INVISIBLE (-2300 2550);
FORCEPROP 1 LAST PATH I15
J 0
(-2300 2550);
DISPLAY 0.617021 (-2300 2550);
PAINT GREEN (-2300 2550);
DISPLAY INVISIBLE (-2300 2550);
FORCEADD P3V3_STBY..1
(-4850 3050);
FORCEPROP 3 LASTPIN (-4850 3000) SIG_NAME P3V3_STBY\g
J 0
(-4840 3010);
DISPLAY 0.659574 (-4840 3010);
PAINT MONO (-4840 3010);
DISPLAY INVISIBLE (-4840 3010);
FORCEPROP 2 LAST CDS_LIB mstr_symbols
J 0
(-4850 3050);
PAINT MONO (-4850 3050);
DISPLAY INVISIBLE (-4850 3050);
FORCEPROP 1 LAST SIZE 1B
J 0
(-4805 3072);
DISPLAY 0.340426 (-4805 3072);
PAINT GREEN (-4805 3072);
DISPLAY INVISIBLE (-4805 3072);
FORCEPROP 1 LAST BODY_TYPE PLUMBING
J 0
(-4895 3007);
DISPLAY 0.340426 (-4895 3007);
PAINT GREEN (-4895 3007);
DISPLAY INVISIBLE (-4895 3007);
FORCEPROP 1 LAST HDL_POWER P3V3_STBY
J 0
(-5150 2925);
DISPLAY 0.872340 (-5150 2925);
PAINT ORANGE (-5150 2925);
DISPLAY INVISIBLE (-5150 2925);
FORCEPROP 1 LAST VOLTAGE 3.3V
J 0
(-4895 3007);
DISPLAY 0.340426 (-4895 3007);
PAINT GREEN (-4895 3007);
DISPLAY INVISIBLE (-4895 3007);
FORCEPROP 1 LAST PATH I16
J 0
(-4805 3052);
DISPLAY 0.340426 (-4805 3052);
PAINT GREEN (-4805 3052);
DISPLAY INVISIBLE (-4805 3052);
FORCEADD RES..2
(-6850 1950);
FORCEPROP 1 LAST PACK_TYPE 0402
J 0
(-6810 1775);
DISPLAY 0.617021 (-6810 1775);
PAINT SKYBLUE (-6810 1775);
FORCEPROP 1 LAST LOCATION R3W1
J 0
(-6805 2075);
DISPLAY 0.617021 (-6805 2075);
PAINT AQUA (-6805 2075);
FORCEPROP 1 LAST MATERIAL CHIP
J 0
(-6810 1875);
DISPLAY 0.617021 (-6810 1875);
PAINT SKYBLUE (-6810 1875);
FORCEPROP 1 LASTPIN (-6850 1850) $PN 2
J 0
(-6845 1860);
DISPLAY 0.787234 (-6845 1860);
PAINT ORANGE (-6845 1860);
FORCEPROP 1 LASTPIN (-6850 2050) $PN 1
J 0
(-6845 2012);
DISPLAY 0.787234 (-6845 2012);
PAINT ORANGE (-6845 2012);
FORCEPROP 1 LAST TOLERANCE 1%
J 0
(-6805 1975);
DISPLAY 0.617021 (-6805 1975);
PAINT SKYBLUE (-6805 1975);
FORCEPROP 1 LAST WATTAGE 1/16W
J 0
(-6810 1925);
DISPLAY 0.617021 (-6810 1925);
PAINT SKYBLUE (-6810 1925);
FORCEPROP 0 LAST NEW_VALUE 470K
J 0
(-6800 2025);
DISPLAY 0.638298 (-6800 2025);
PAINT BROWN (-6800 2025);
DISPLAY BOTH (-6800 2025);
FORCEPROP 0 LAST CONFIG 64.47035.L0L
J 0
(-6800 1825);
DISPLAY 0.638298 (-6800 1825);
PAINT BROWN (-6800 1825);
DISPLAY BOTH (-6800 1825);
FORCEPROP 1 LAST VALUE 1.00K
J 0
(-6805 2025);
DISPLAY 0.617021 (-6805 2025);
PAINT SKYBLUE (-6805 2025);
DISPLAY INVISIBLE (-6805 2025);
FORCEPROP 1 LAST PART_NUMBER G21796-026
J 0
(-6810 1825);
DISPLAY 0.617021 (-6810 1825);
PAINT BLUE (-6810 1825);
DISPLAY INVISIBLE (-6810 1825);
FORCEPROP 0 LAST SEC 1
J 0
(-6800 2125);
DISPLAY 0.680851 (-6800 2125);
PAINT MONO (-6800 2125);
DISPLAY INVISIBLE (-6800 2125);
FORCEPROP 2 LAST SEC_TYPE 0402
J 0
(-6800 2175);
DISPLAY 1.021277 (-6800 2175);
PAINT ORANGE (-6800 2175);
DISPLAY INVISIBLE (-6800 2175);
FORCEPROP 0 LAST ROOM BMC_DEBUG_HEADER
J 0
(-6800 2175);
DISPLAY 1.021277 (-6800 2175);
PAINT ORANGE (-6800 2175);
DISPLAY INVISIBLE (-6800 2175);
FORCEPROP 2 LAST CDS_LIB mstr_discrete
J 0
(-6850 1950);
PAINT MONO (-6850 1950);
DISPLAY INVISIBLE (-6850 1950);
FORCEPROP 1 LAST PATH I2
J 0
(-6800 2125);
DISPLAY 0.978723 (-6800 2125);
PAINT WHITE (-6800 2125);
DISPLAY INVISIBLE (-6800 2125);
FORCEADD GND..1
(-2050 2800);
FORCEPROP 3 LASTPIN (-2050 2850) SIG_NAME GND\g
J 0
(-2040 2860);
DISPLAY 0.659574 (-2040 2860);
PAINT MONO (-2040 2860);
DISPLAY INVISIBLE (-2040 2860);
FORCEPROP 2 LAST CDS_LIB mstr_symbols
J 0
(-2050 2800);
PAINT MONO (-2050 2800);
DISPLAY INVISIBLE (-2050 2800);
FORCEPROP 1 LAST HDL_POWER GND
J 0
(-2050 2950);
DISPLAY 0.872340 (-2050 2950);
PAINT GREEN (-2050 2950);
DISPLAY INVISIBLE (-2050 2950);
FORCEPROP 1 LAST SIZE 1B
J 0
(-1975 2750);
DISPLAY 0.872340 (-1975 2750);
PAINT AQUA (-1975 2750);
DISPLAY INVISIBLE (-1975 2750);
FORCEPROP 1 LAST BODY_TYPE PLUMBING
J 0
(-2095 2757);
DISPLAY 0.340426 (-2095 2757);
PAINT GREEN (-2095 2757);
DISPLAY INVISIBLE (-2095 2757);
FORCEPROP 1 LAST VOLTAGE 0.0V
J 0
(-2095 2757);
DISPLAY 0.340426 (-2095 2757);
PAINT GREEN (-2095 2757);
DISPLAY INVISIBLE (-2095 2757);
FORCEPROP 1 LAST PATH I20
J 0
(-1975 2800);
DISPLAY 0.872340 (-1975 2800);
PAINT AQUA (-1975 2800);
DISPLAY INVISIBLE (-1975 2800);
FORCEADD OFFPAGE..2
(-1400 2550);
FORCEPROP 2 LAST $XR2 146 
J 0
(-971 2550);
DISPLAY 0.638298 (-971 2550);
PAINT MONO (-971 2550);
FORCEPROP 2 LAST $XR1 119 
J 0
(-1091 2550);
DISPLAY 0.638298 (-1091 2550);
PAINT MONO (-1091 2550);
FORCEPROP 2 LAST $XR0 133 
J 0
(-1211 2550);
DISPLAY 0.638298 (-1211 2550);
PAINT MONO (-1211 2550);
FORCEPROP 2 LAST PATH I22
J 0
(-1225 2625);
DISPLAY 1.021277 (-1225 2625);
PAINT ORANGE (-1225 2625);
DISPLAY INVISIBLE (-1225 2625);
FORCEPROP 1 LAST OFFPAGE TRUE
J 0
(-1075 2425);
DISPLAY 0.872340 (-1075 2425);
PAINT GREEN (-1075 2425);
DISPLAY INVISIBLE (-1075 2425);
FORCEPROP 1 LAST COMMENT_BODY TRUE
J 0
(-1445 2455);
DISPLAY 0.872340 (-1445 2455);
PAINT GREEN (-1445 2455);
DISPLAY INVISIBLE (-1445 2455);
FORCEPROP 2 LAST CDS_LIB mstr_standard
J 0
(-1400 2550);
PAINT MONO (-1400 2550);
DISPLAY INVISIBLE (-1400 2550);
FORCEADD P3V3_STBY..1
(-3200 4800);
FORCEPROP 3 LASTPIN (-3200 4750) SIG_NAME P3V3_STBY\g
J 0
(-3190 4760);
DISPLAY 0.659574 (-3190 4760);
PAINT MONO (-3190 4760);
DISPLAY INVISIBLE (-3190 4760);
FORCEPROP 1 LAST PATH I24
J 0
(-3155 4802);
DISPLAY 0.340426 (-3155 4802);
PAINT GREEN (-3155 4802);
DISPLAY INVISIBLE (-3155 4802);
FORCEPROP 1 LAST VOLTAGE 3.3V
J 0
(-3245 4757);
DISPLAY 0.340426 (-3245 4757);
PAINT GREEN (-3245 4757);
DISPLAY INVISIBLE (-3245 4757);
FORCEPROP 2 LAST CDS_LIB mstr_symbols
J 0
(-3200 4800);
PAINT MONO (-3200 4800);
DISPLAY INVISIBLE (-3200 4800);
FORCEPROP 1 LAST SIZE 1B
J 0
(-3155 4822);
DISPLAY 0.340426 (-3155 4822);
PAINT GREEN (-3155 4822);
DISPLAY INVISIBLE (-3155 4822);
FORCEPROP 1 LAST BODY_TYPE PLUMBING
J 0
(-3245 4757);
DISPLAY 0.340426 (-3245 4757);
PAINT GREEN (-3245 4757);
DISPLAY INVISIBLE (-3245 4757);
FORCEPROP 1 LAST HDL_POWER P3V3_STBY
J 0
(-3500 4675);
DISPLAY 0.872340 (-3500 4675);
PAINT ORANGE (-3500 4675);
DISPLAY INVISIBLE (-3500 4675);
FORCEADD NPN..1
(-3250 3850);
FORCEPROP 1 LAST VALUE MMBT3904
J 0
(-3100 3850);
DISPLAY 0.617021 (-3100 3850);
PAINT SKYBLUE (-3100 3850);
FORCEPROP 1 LASTPIN (-3350 3850) $PN 1
J 0
(-3405 3875);
DISPLAY 0.957447 (-3405 3875);
PAINT GREEN (-3405 3875);
FORCEPROP 1 LASTPIN (-3200 3950) $PN 3
J 0
(-3181 3960);
DISPLAY 0.957447 (-3181 3960);
PAINT GREEN (-3181 3960);
FORCEPROP 1 LAST MATERIAL IC
J 0
(-3100 3800);
DISPLAY 0.617021 (-3100 3800);
PAINT SKYBLUE (-3100 3800);
FORCEPROP 1 LAST LOCATION Q9W2
J 0
(-3100 3900);
DISPLAY 0.617021 (-3100 3900);
PAINT AQUA (-3100 3900);
FORCEPROP 1 LAST PACK_TYPE SM
J 0
(-3100 3750);
DISPLAY 0.617021 (-3100 3750);
PAINT SKYBLUE (-3100 3750);
FORCEPROP 1 LAST PART_NUMBER C52245-001
J 0
(-3100 3700);
DISPLAY 0.617021 (-3100 3700);
PAINT BLUE (-3100 3700);
FORCEPROP 1 LASTPIN (-3200 3750) $PN 2
J 0
(-3175 3700);
DISPLAY 0.957447 (-3175 3700);
PAINT GREEN (-3175 3700);
FORCEPROP 1 LAST PATH I29
J 0
(-3100 3950);
DISPLAY 0.978723 (-3100 3950);
PAINT BLUE (-3100 3950);
DISPLAY INVISIBLE (-3100 3950);
FORCEPROP 2 LAST CDS_LIB mstr_discrete
J 0
(-3250 3850);
PAINT MONO (-3250 3850);
DISPLAY INVISIBLE (-3250 3850);
FORCEPROP 2 LAST ROOM SB
J 0
(-3100 3950);
DISPLAY 1.404255 (-3100 3950);
PAINT ORANGE (-3100 3950);
DISPLAY INVISIBLE (-3100 3950);
FORCEPROP 2 LAST SEC_TYPE SM
J 0
(-3100 4000);
DISPLAY 1.021277 (-3100 4000);
PAINT ORANGE (-3100 4000);
DISPLAY INVISIBLE (-3100 4000);
FORCEPROP 0 LAST SEC 1
J 0
(-3100 3950);
DISPLAY 0.680851 (-3100 3950);
PAINT MONO (-3100 3950);
DISPLAY INVISIBLE (-3100 3950);
FORCEADD GND..1
(-6850 1700);
FORCEPROP 3 LASTPIN (-6850 1750) SIG_NAME GND\g
J 0
(-6840 1760);
DISPLAY 0.659574 (-6840 1760);
PAINT MONO (-6840 1760);
DISPLAY INVISIBLE (-6840 1760);
FORCEPROP 1 LAST PATH I3
J 0
(-6775 1700);
DISPLAY 0.872340 (-6775 1700);
PAINT AQUA (-6775 1700);
DISPLAY INVISIBLE (-6775 1700);
FORCEPROP 1 LAST VOLTAGE 0.0V
J 0
(-6895 1657);
DISPLAY 0.340426 (-6895 1657);
PAINT GREEN (-6895 1657);
DISPLAY INVISIBLE (-6895 1657);
FORCEPROP 1 LAST BODY_TYPE PLUMBING
J 0
(-6895 1657);
DISPLAY 0.340426 (-6895 1657);
PAINT GREEN (-6895 1657);
DISPLAY INVISIBLE (-6895 1657);
FORCEPROP 2 LAST CDS_LIB mstr_symbols
J 0
(-6850 1700);
PAINT MONO (-6850 1700);
DISPLAY INVISIBLE (-6850 1700);
FORCEPROP 1 LAST SIZE 1B
J 0
(-6775 1650);
DISPLAY 0.872340 (-6775 1650);
PAINT AQUA (-6775 1650);
DISPLAY INVISIBLE (-6775 1650);
FORCEPROP 1 LAST HDL_POWER GND
J 0
(-6850 1850);
DISPLAY 0.872340 (-6850 1850);
PAINT GREEN (-6850 1850);
DISPLAY INVISIBLE (-6850 1850);
FORCEADD FET_N..8
(-4850 2250);
FORCEPROP 1 LASTPIN (-4850 2050) $PN 2
J 2
(-4792 2050);
DISPLAY 0.872340 (-4792 2050);
PAINT WHITE (-4792 2050);
FORCEPROP 1 LAST PART_NUMBER C79254-001
J 0
(-4650 2075);
DISPLAY 0.617021 (-4650 2075);
PAINT BLUE (-4650 2075);
FORCEPROP 1 LAST LOCATION Q9W1
J 0
(-4650 2275);
DISPLAY 0.617021 (-4650 2275);
PAINT AQUA (-4650 2275);
FORCEPROP 1 LAST VALUE 2N7002
J 0
(-4650 2225);
DISPLAY 0.617021 (-4650 2225);
PAINT SKYBLUE (-4650 2225);
FORCEPROP 1 LAST MATERIAL FET
J 0
(-4650 2175);
DISPLAY 0.617021 (-4650 2175);
PAINT SKYBLUE (-4650 2175);
FORCEPROP 1 LASTPIN (-4850 2450) $PN 3
J 2
(-4797 2415);
DISPLAY 0.872340 (-4797 2415);
PAINT WHITE (-4797 2415);
FORCEPROP 1 LASTPIN (-5050 2150) $PN 1
J 2
(-5047 2165);
DISPLAY 0.872340 (-5047 2165);
PAINT WHITE (-5047 2165);
FORCEPROP 1 LAST PACK_TYPE SOT23LF
J 0
(-4650 2100);
DISPLAY 0.978723 (-4650 2100);
PAINT SKYBLUE (-4650 2100);
DISPLAY INVISIBLE (-4650 2100);
FORCEPROP 0 LAST SEC 1
J 0
(-4650 2300);
DISPLAY 0.680851 (-4650 2300);
PAINT MONO (-4650 2300);
DISPLAY INVISIBLE (-4650 2300);
FORCEPROP 2 LAST SEC_TYPE SOT23LF
J 0
(-4650 2350);
DISPLAY 1.021277 (-4650 2350);
PAINT ORANGE (-4650 2350);
DISPLAY INVISIBLE (-4650 2350);
FORCEPROP 2 LAST CDS_LIB mstr_discrete
J 0
(-4850 2250);
PAINT MONO (-4850 2250);
DISPLAY INVISIBLE (-4850 2250);
FORCEPROP 1 LAST PATH I30
J 0
(-4650 2300);
DISPLAY 0.978723 (-4650 2300);
PAINT BLUE (-4650 2300);
DISPLAY INVISIBLE (-4650 2300);
FORCEPROP 0 LAST ROOM HOT_SWAP
J 0
(-4650 2350);
DISPLAY 1.021277 (-4650 2350);
PAINT ORANGE (-4650 2350);
DISPLAY INVISIBLE (-4650 2350);
FORCEADD 47KR2F-GP..1
R 1
(-4325 3850);
FORCEPROP 1 LAST VALUE 47KR2F-GP
J 0
(-4425 3900);
DISPLAY 0.617021 (-4425 3900);
PAINT GREEN (-4425 3900);
FORCEPROP 2 LAST ATTRIBUTE 47KOHM
J 0
(-4450 3775);
DISPLAY 0.638298 (-4450 3775);
PAINT GREEN (-4450 3775);
FORCEPROP 2 LAST RATED 1/16W
J 0
(-4450 3675);
DISPLAY 0.638298 (-4450 3675);
PAINT GREEN (-4450 3675);
FORCEPROP 2 LAST TOLERANCE 1%
J 0
(-4450 3725);
DISPLAY 0.638298 (-4450 3725);
PAINT GREEN (-4450 3725);
FORCEPROP 1 LAST LOCATION R3W4
J 0
(-4425 3950);
DISPLAY 0.617021 (-4425 3950);
PAINT GREEN (-4425 3950);
FORCEPROP 2 LAST PACK_SIZE 0402
J 0
(-4450 3625);
DISPLAY 0.638298 (-4450 3625);
PAINT GREEN (-4450 3625);
FORCEPROP 1 LAST CDS_LMAN_SYM_OUTLINE -50,75,50,-75
R 1
J 0
(-4325 3850);
DISPLAY 0.468085 (-4325 3850);
PAINT GREEN (-4325 3850);
DISPLAY INVISIBLE (-4325 3850);
FORCEPROP 1 LAST PATH I31
R 1
J 0
(-4325 3850);
DISPLAY 0.617021 (-4325 3850);
PAINT GREEN (-4325 3850);
DISPLAY INVISIBLE (-4325 3850);
FORCEPROP 2 LAST CDS_LIB w_hdl
R 1
J 0
(-4325 3850);
PAINT MONO (-4325 3850);
DISPLAY INVISIBLE (-4325 3850);
FORCEPROP 1 LAST PART_NUMBER 64.47025.6DL
R 1
J 0
(-4325 3850);
DISPLAY 0.617021 (-4325 3850);
PAINT GREEN (-4325 3850);
DISPLAY INVISIBLE (-4325 3850);
FORCEPROP 1 LAST PACK_TYPE RCL_GP
R 1
J 0
(-4325 3850);
DISPLAY 0.617021 (-4325 3850);
PAINT GREEN (-4325 3850);
DISPLAY INVISIBLE (-4325 3850);
FORCEADD RES..1
(-6150 3350);
FORCEPROP 1 LASTPIN (-6050 3350) $PN 2
J 0
(-6088 3362);
DISPLAY 0.787234 (-6088 3362);
PAINT ORANGE (-6088 3362);
FORCEPROP 1 LASTPIN (-6250 3350) $PN 1
J 0
(-6238 3362);
DISPLAY 0.787234 (-6238 3362);
PAINT ORANGE (-6238 3362);
FORCEPROP 1 LAST LOCATION R8W1
J 0
(-6200 3400);
DISPLAY 0.617021 (-6200 3400);
PAINT AQUA (-6200 3400);
FORCEPROP 1 LAST PART_NUMBER G21497-005
J 0
(-6300 3300);
DISPLAY 0.617021 (-6300 3300);
PAINT BLUE (-6300 3300);
FORCEPROP 1 LAST TOLERANCE 5%
J 0
(-6200 3250);
DISPLAY 0.617021 (-6200 3250);
PAINT SKYBLUE (-6200 3250);
FORCEPROP 1 LAST PACK_TYPE 0402
J 0
(-6075 3250);
DISPLAY 0.617021 (-6075 3250);
PAINT SKYBLUE (-6075 3250);
FORCEPROP 0 LAST POP NOPOP
J 0
(-6025 3375);
DISPLAY 1.021277 (-6025 3375);
PAINT RED (-6025 3375);
FORCEPROP 1 LAST VALUE 0.0
J 2
(-6250 3250);
DISPLAY 0.617021 (-6250 3250);
PAINT SKYBLUE (-6250 3250);
FORCEPROP 1 LAST WATTAGE 1/16W
J 2
(-6175 3200);
DISPLAY 0.617021 (-6175 3200);
PAINT SKYBLUE (-6175 3200);
FORCEPROP 1 LAST MATERIAL CHIP
J 0
(-6150 3200);
DISPLAY 0.617021 (-6150 3200);
PAINT SKYBLUE (-6150 3200);
FORCEPROP 2 LAST CDS_LIB mstr_discrete
J 0
(-6150 3350);
PAINT MONO (-6150 3350);
DISPLAY INVISIBLE (-6150 3350);
FORCEPROP 1 LAST PATH I34
J 0
(-6200 3500);
DISPLAY 0.978723 (-6200 3500);
PAINT WHITE (-6200 3500);
DISPLAY INVISIBLE (-6200 3500);
FORCEPROP 2 LAST ROOM PVCCIN_CPU0_VR
J 0
(-6200 3450);
DISPLAY 1.361702 (-6200 3450);
PAINT ORANGE (-6200 3450);
DISPLAY INVISIBLE (-6200 3450);
FORCEPROP 0 LAST SEC 1
J 0
(-6200 3450);
DISPLAY 0.680851 (-6200 3450);
PAINT MONO (-6200 3450);
DISPLAY INVISIBLE (-6200 3450);
FORCEPROP 2 LAST SEC_TYPE 0402
J 0
(-6200 3550);
DISPLAY 1.021277 (-6200 3550);
PAINT ORANGE (-6200 3550);
DISPLAY INVISIBLE (-6200 3550);
FORCEADD P5V_STBY..1
(-2050 3250);
FORCEPROP 3 LASTPIN (-2050 3200) SIG_NAME P5V_STBY\g
J 0
(-2040 3210);
DISPLAY 0.659574 (-2040 3210);
PAINT MONO (-2040 3210);
DISPLAY INVISIBLE (-2040 3210);
FORCEPROP 2 LAST CDS_LIB mstr_symbols
J 0
(-2050 3250);
PAINT MONO (-2050 3250);
DISPLAY INVISIBLE (-2050 3250);
FORCEPROP 1 LAST PATH I35
J 0
(-2005 3252);
DISPLAY 0.340426 (-2005 3252);
PAINT GREEN (-2005 3252);
DISPLAY INVISIBLE (-2005 3252);
FORCEPROP 1 LAST HDL_POWER P5V_STBY
J 0
(-2350 3125);
DISPLAY 0.872340 (-2350 3125);
PAINT ORANGE (-2350 3125);
DISPLAY INVISIBLE (-2350 3125);
FORCEPROP 1 LAST BODY_TYPE PLUMBING
J 0
(-2095 3207);
DISPLAY 0.340426 (-2095 3207);
PAINT GREEN (-2095 3207);
DISPLAY INVISIBLE (-2095 3207);
FORCEPROP 1 LAST VOLTAGE 5.0V
J 0
(-2095 3207);
DISPLAY 0.340426 (-2095 3207);
PAINT SKYBLUE (-2095 3207);
DISPLAY INVISIBLE (-2095 3207);
FORCEPROP 1 LAST SIZE 1B
J 0
(-2005 3272);
DISPLAY 0.340426 (-2005 3272);
PAINT GREEN (-2005 3272);
DISPLAY INVISIBLE (-2005 3272);
FORCEADD RES..2
(-4850 2850);
FORCEPROP 1 LASTPIN (-4850 2750) $PN 2
J 0
(-4845 2760);
DISPLAY 0.787234 (-4845 2760);
PAINT ORANGE (-4845 2760);
FORCEPROP 1 LAST MATERIAL EMPTY
J 0
(-4810 2775);
DISPLAY 0.617021 (-4810 2775);
PAINT RED (-4810 2775);
FORCEPROP 1 LAST WATTAGE 1/16W
J 0
(-4810 2825);
DISPLAY 0.617021 (-4810 2825);
PAINT SKYBLUE (-4810 2825);
FORCEPROP 1 LAST LOCATION R3W3
J 0
(-4805 2975);
DISPLAY 0.617021 (-4805 2975);
PAINT AQUA (-4805 2975);
FORCEPROP 1 LAST VALUE 10.0K
J 0
(-4805 2925);
DISPLAY 0.617021 (-4805 2925);
PAINT SKYBLUE (-4805 2925);
FORCEPROP 1 LAST TOLERANCE 1%
J 0
(-4805 2875);
DISPLAY 0.617021 (-4805 2875);
PAINT SKYBLUE (-4805 2875);
FORCEPROP 1 LAST PART_NUMBER G21796-016
J 0
(-4810 2725);
DISPLAY 0.617021 (-4810 2725);
PAINT BLUE (-4810 2725);
FORCEPROP 1 LASTPIN (-4850 2950) $PN 1
J 0
(-4845 2912);
DISPLAY 0.787234 (-4845 2912);
PAINT ORANGE (-4845 2912);
FORCEPROP 1 LAST PACK_TYPE 0402
J 0
(-4810 2675);
DISPLAY 0.617021 (-4810 2675);
PAINT SKYBLUE (-4810 2675);
FORCEPROP 2 LAST SEC 1
J 0
(-4800 3075);
DISPLAY 0.680851 (-4800 3075);
PAINT MONO (-4800 3075);
DISPLAY INVISIBLE (-4800 3075);
FORCEPROP 2 LAST SEC_TYPE 0402
J 0
(-4800 3075);
DISPLAY 1.021277 (-4800 3075);
PAINT ORANGE (-4800 3075);
DISPLAY INVISIBLE (-4800 3075);
FORCEPROP 2 LAST CDS_LIB mstr_discrete
J 0
(-4850 2850);
PAINT MONO (-4850 2850);
DISPLAY INVISIBLE (-4850 2850);
FORCEPROP 1 LAST PATH I36
J 0
(-4800 3025);
DISPLAY 0.978723 (-4800 3025);
PAINT WHITE (-4800 3025);
DISPLAY INVISIBLE (-4800 3025);
FORCEPROP 2 LAST ROOM DB1200ZL
J 0
(-4800 3075);
DISPLAY 1.021277 (-4800 3075);
PAINT ORANGE (-4800 3075);
DISPLAY INVISIBLE (-4800 3075);
FORCEPROP 2 LAST BOM_COST SYS_CLOCK
J 0
(-4800 3175);
DISPLAY 1.021277 (-4800 3175);
PAINT ORANGE (-4800 3175);
DISPLAY INVISIBLE (-4800 3175);
FORCEADD CAP_A..1
(-2050 3000);
FORCEPROP 1 LAST PART_NUMBER A36096-030
J 0
(-2000 2850);
DISPLAY 0.617021 (-2000 2850);
PAINT BLUE (-2000 2850);
FORCEPROP 1 LAST TOLERANCE 10%
J 0
(-2000 2950);
DISPLAY 0.617021 (-2000 2950);
PAINT SKYBLUE (-2000 2950);
FORCEPROP 1 LASTPIN (-2050 2900) $PN 2
J 0
(-2040 2880);
DISPLAY 0.617021 (-2040 2880);
PAINT ORANGE (-2040 2880);
FORCEPROP 1 LASTPIN (-2050 3100) $PN 1
J 0
(-2040 3080);
DISPLAY 0.617021 (-2040 3080);
PAINT ORANGE (-2040 3080);
FORCEPROP 1 LAST LOCATION C8W2
J 0
(-2000 3100);
DISPLAY 0.617021 (-2000 3100);
PAINT AQUA (-2000 3100);
FORCEPROP 1 LAST VALUE 0.1UF
J 0
(-2000 3050);
DISPLAY 0.617021 (-2000 3050);
PAINT SKYBLUE (-2000 3050);
FORCEPROP 1 LAST VOLTAGE 16V
J 0
(-2000 3000);
DISPLAY 0.617021 (-2000 3000);
PAINT SKYBLUE (-2000 3000);
FORCEPROP 1 LAST MATERIAL X7R
J 0
(-2000 2900);
DISPLAY 0.617021 (-2000 2900);
PAINT SKYBLUE (-2000 2900);
FORCEPROP 1 LAST PACK_TYPE 0402V
J 0
(-2000 2800);
DISPLAY 0.617021 (-2000 2800);
PAINT SKYBLUE (-2000 2800);
FORCEPROP 2 LAST SEC 1
J 0
(-2000 3225);
DISPLAY 0.680851 (-2000 3225);
PAINT MONO (-2000 3225);
DISPLAY INVISIBLE (-2000 3225);
FORCEPROP 2 LAST SEC_TYPE 0402V
J 0
(-2000 3225);
DISPLAY 1.021277 (-2000 3225);
PAINT ORANGE (-2000 3225);
DISPLAY INVISIBLE (-2000 3225);
FORCEPROP 2 LAST ROOM VDDQ_KLM_PWR_VR
J 0
(-2000 3150);
DISPLAY 1.361702 (-2000 3150);
PAINT ORANGE (-2000 3150);
DISPLAY INVISIBLE (-2000 3150);
FORCEPROP 2 LAST CDS_SEC 1
J 0
(-2000 3150);
PAINT ORANGE (-2000 3150);
DISPLAY INVISIBLE (-2000 3150);
FORCEPROP 2 LAST CDS_LIB dev_discrete
J 0
(-2050 3000);
PAINT ORANGE (-2050 3000);
DISPLAY INVISIBLE (-2050 3000);
FORCEPROP 1 LAST PATH I37
J 0
(-2000 3150);
DISPLAY 0.978723 (-2000 3150);
PAINT WHITE (-2000 3150);
DISPLAY INVISIBLE (-2000 3150);
FORCEPROP 2 LAST CDS_LOCATION C8W2
J 0
(-2000 3100);
DISPLAY 0.617021 (-2000 3100);
PAINT AQUA (-2000 3100);
DISPLAY INVISIBLE (-2000 3100);
FORCEADD RES..2
R 2
(-2300 4450);
FORCEPROP 1 LAST WATTAGE 1/16W
J 2
(-2340 4375);
DISPLAY 0.617021 (-2340 4375);
PAINT SKYBLUE (-2340 4375);
FORCEPROP 1 LAST TOLERANCE 1%
J 2
(-2345 4425);
DISPLAY 0.617021 (-2345 4425);
PAINT SKYBLUE (-2345 4425);
FORCEPROP 1 LASTPIN (-2300 4350) $PN 2
J 2
(-2305 4360);
DISPLAY 0.787234 (-2305 4360);
PAINT ORANGE (-2305 4360);
FORCEPROP 1 LAST MATERIAL CHIP
J 2
(-2340 4475);
DISPLAY 0.617021 (-2340 4475);
PAINT SKYBLUE (-2340 4475);
FORCEPROP 1 LASTPIN (-2300 4550) $PN 1
J 2
(-2305 4512);
DISPLAY 0.787234 (-2305 4512);
PAINT ORANGE (-2305 4512);
FORCEPROP 1 LAST LOCATION R3W6
J 2
(-2345 4575);
DISPLAY 0.617021 (-2345 4575);
PAINT AQUA (-2345 4575);
FORCEPROP 1 LAST PACK_TYPE 0402
J 2
(-2340 4275);
DISPLAY 0.617021 (-2340 4275);
PAINT SKYBLUE (-2340 4275);
FORCEPROP 1 LAST PART_NUMBER G21796-072
J 2
(-2340 4325);
DISPLAY 0.617021 (-2340 4325);
PAINT BLUE (-2340 4325);
FORCEPROP 1 LAST VALUE 4.75K
J 2
(-2345 4525);
DISPLAY 0.617021 (-2345 4525);
PAINT SKYBLUE (-2345 4525);
FORCEPROP 1 LAST PATH I48
J 2
(-2350 4625);
DISPLAY 0.978723 (-2350 4625);
PAINT WHITE (-2350 4625);
DISPLAY INVISIBLE (-2350 4625);
FORCEPROP 0 LAST CDS_SEC 1
J 0
(-2325 4625);
DISPLAY INVISIBLE (-2325 4625);
FORCEPROP 0 LAST CDS_LOCATION R3W6
J 0
(-2325 4625);
DISPLAY INVISIBLE (-2325 4625);
FORCEPROP 2 LAST NO_XNET_CONNECTION 1
J 0
(-2350 4675);
PAINT MONO (-2350 4675);
DISPLAY INVISIBLE (-2350 4675);
FORCEPROP 2 LAST BOM_COST MIO_BIOS_MEM
J 0
(-2325 4675);
DISPLAY 1.021277 (-2325 4675);
PAINT ORANGE (-2325 4675);
DISPLAY INVISIBLE (-2325 4675);
FORCEPROP 2 LAST ROOM SB_SPI
J 0
(-2325 4625);
DISPLAY 1.021277 (-2325 4625);
PAINT ORANGE (-2325 4625);
DISPLAY INVISIBLE (-2325 4625);
FORCEPROP 2 LAST CDS_LIB mstr_discrete
J 0
(-2300 4450);
PAINT MONO (-2300 4450);
DISPLAY INVISIBLE (-2300 4450);
FORCEPROP 2 LAST SEC_TYPE 0402
J 0
(-2350 4675);
DISPLAY 1.021277 (-2350 4675);
PAINT ORANGE (-2350 4675);
DISPLAY INVISIBLE (-2350 4675);
FORCEPROP 0 LAST SEC 1
J 0
(-2325 4625);
DISPLAY 0.680851 (-2325 4625);
PAINT MONO (-2325 4625);
DISPLAY INVISIBLE (-2325 4625);
FORCEADD NPN..1
(-2350 4100);
FORCEPROP 1 LASTPIN (-2300 4000) $PN 2
J 0
(-2275 3950);
DISPLAY 0.957447 (-2275 3950);
PAINT GREEN (-2275 3950);
FORCEPROP 1 LASTPIN (-2300 4200) $PN 3
J 0
(-2281 4210);
DISPLAY 0.957447 (-2281 4210);
PAINT GREEN (-2281 4210);
FORCEPROP 1 LAST MATERIAL IC
J 0
(-2200 4050);
DISPLAY 0.617021 (-2200 4050);
PAINT SKYBLUE (-2200 4050);
FORCEPROP 1 LAST LOCATION Q9W3
J 0
(-2200 4150);
DISPLAY 0.617021 (-2200 4150);
PAINT AQUA (-2200 4150);
FORCEPROP 1 LAST VALUE MMBT3904
J 0
(-2200 4100);
DISPLAY 0.617021 (-2200 4100);
PAINT SKYBLUE (-2200 4100);
FORCEPROP 1 LASTPIN (-2450 4100) $PN 1
J 0
(-2505 4125);
DISPLAY 0.957447 (-2505 4125);
PAINT GREEN (-2505 4125);
FORCEPROP 1 LAST PART_NUMBER C52245-001
J 0
(-2200 3950);
DISPLAY 0.617021 (-2200 3950);
PAINT BLUE (-2200 3950);
FORCEPROP 1 LAST PACK_TYPE SM
J 0
(-2200 4000);
DISPLAY 0.617021 (-2200 4000);
PAINT SKYBLUE (-2200 4000);
FORCEPROP 1 LAST PATH I49
J 0
(-2200 4200);
DISPLAY 0.978723 (-2200 4200);
PAINT BLUE (-2200 4200);
DISPLAY INVISIBLE (-2200 4200);
FORCEPROP 0 LAST CDS_SEC 1
J 0
(-2200 4200);
DISPLAY INVISIBLE (-2200 4200);
FORCEPROP 0 LAST CDS_LOCATION Q9W3
J 0
(-2200 4200);
DISPLAY INVISIBLE (-2200 4200);
FORCEPROP 2 LAST ROOM SB
J 0
(-2200 4200);
DISPLAY 1.404255 (-2200 4200);
PAINT ORANGE (-2200 4200);
DISPLAY INVISIBLE (-2200 4200);
FORCEPROP 2 LAST CDS_LIB mstr_discrete
J 0
(-2350 4100);
PAINT MONO (-2350 4100);
DISPLAY INVISIBLE (-2350 4100);
FORCEPROP 2 LAST SEC_TYPE SM
J 0
(-2200 4250);
DISPLAY 1.021277 (-2200 4250);
PAINT ORANGE (-2200 4250);
DISPLAY INVISIBLE (-2200 4250);
FORCEPROP 0 LAST SEC 1
J 0
(-2200 4200);
DISPLAY 0.680851 (-2200 4200);
PAINT MONO (-2200 4200);
DISPLAY INVISIBLE (-2200 4200);
FORCEADD OFFPAGE..1
(-6150 3850);
FORCEPROP 2 LAST $XR2 184 
J 0
(-6642 3850);
DISPLAY 0.638298 (-6642 3850);
PAINT MONO (-6642 3850);
FORCEPROP 2 LAST $XR1 157 
J 0
(-6522 3850);
DISPLAY 0.638298 (-6522 3850);
PAINT MONO (-6522 3850);
FORCEPROP 2 LAST $XR0 119 
J 0
(-6402 3850);
DISPLAY 0.638298 (-6402 3850);
PAINT MONO (-6402 3850);
FORCEPROP 2 LAST CDS_LIB mstr_standard
J 0
(-6150 3850);
PAINT MONO (-6150 3850);
DISPLAY INVISIBLE (-6150 3850);
FORCEPROP 1 LAST OFFPAGE TRUE
J 0
(-5825 3725);
DISPLAY 0.872340 (-5825 3725);
PAINT GREEN (-5825 3725);
DISPLAY INVISIBLE (-5825 3725);
FORCEPROP 1 LAST COMMENT_BODY TRUE
J 0
(-6025 3750);
DISPLAY 0.872340 (-6025 3750);
PAINT GREEN (-6025 3750);
DISPLAY INVISIBLE (-6025 3750);
FORCEPROP 2 LAST PATH I5
J 0
(-6100 3925);
DISPLAY 1.021277 (-6100 3925);
PAINT ORANGE (-6100 3925);
DISPLAY INVISIBLE (-6100 3925);
FORCEADD GND..1
(-2300 3850);
FORCEPROP 3 LASTPIN (-2300 3900) SIG_NAME GND\g
J 0
(-2290 3910);
DISPLAY 0.659574 (-2290 3910);
PAINT MONO (-2290 3910);
DISPLAY INVISIBLE (-2290 3910);
FORCEPROP 1 LAST PATH I50
J 0
(-2225 3850);
DISPLAY 0.872340 (-2225 3850);
PAINT AQUA (-2225 3850);
DISPLAY INVISIBLE (-2225 3850);
FORCEPROP 2 LAST CDS_LIB mstr_symbols
J 0
(-2300 3850);
PAINT MONO (-2300 3850);
DISPLAY INVISIBLE (-2300 3850);
FORCEPROP 1 LAST SIZE 1B
J 0
(-2225 3800);
DISPLAY 0.872340 (-2225 3800);
PAINT AQUA (-2225 3800);
DISPLAY INVISIBLE (-2225 3800);
FORCEPROP 1 LAST HDL_POWER GND
J 0
(-2300 4000);
DISPLAY 0.872340 (-2300 4000);
PAINT GREEN (-2300 4000);
DISPLAY INVISIBLE (-2300 4000);
FORCEPROP 1 LAST BODY_TYPE PLUMBING
J 0
(-2345 3807);
DISPLAY 0.340426 (-2345 3807);
PAINT GREEN (-2345 3807);
DISPLAY INVISIBLE (-2345 3807);
FORCEPROP 1 LAST VOLTAGE 0.0V
J 0
(-2345 3807);
DISPLAY 0.340426 (-2345 3807);
PAINT GREEN (-2345 3807);
DISPLAY INVISIBLE (-2345 3807);
FORCEADD OFFPAGE..2
(-1550 4300);
FORCEPROP 2 LAST $XR0 146 
J 0
(-1361 4300);
DISPLAY 0.638298 (-1361 4300);
PAINT MONO (-1361 4300);
FORCEPROP 1 LAST COMMENT_BODY TRUE
J 0
(-1595 4205);
DISPLAY 0.872340 (-1595 4205);
PAINT GREEN (-1595 4205);
DISPLAY INVISIBLE (-1595 4205);
FORCEPROP 1 LAST OFFPAGE TRUE
J 0
(-1225 4175);
DISPLAY 0.872340 (-1225 4175);
PAINT GREEN (-1225 4175);
DISPLAY INVISIBLE (-1225 4175);
FORCEPROP 2 LAST CDS_LIB mstr_standard
J 0
(-1550 4300);
PAINT MONO (-1550 4300);
DISPLAY INVISIBLE (-1550 4300);
FORCEPROP 2 LAST PATH I51
J 0
(-1350 4350);
DISPLAY 1.021277 (-1350 4350);
PAINT ORANGE (-1350 4350);
DISPLAY INVISIBLE (-1350 4350);
FORCEADD SC1U16V3KX-2GP..1
R 1
(-6625 2150);
FORCEPROP 2 LAST PACK_SIZE 0603
J 0
(-6700 2200);
DISPLAY 0.638298 (-6700 2200);
PAINT GREEN (-6700 2200);
FORCEPROP 2 LAST RATED 16V
J 0
(-6700 2350);
DISPLAY 0.638298 (-6700 2350);
PAINT GREEN (-6700 2350);
FORCEPROP 1 LAST LOCATION C8W1
J 0
(-6705 2500);
DISPLAY 0.617021 (-6705 2500);
PAINT GREEN (-6705 2500);
FORCEPROP 2 LAST TYPE X5R
J 0
(-6700 2250);
DISPLAY 0.638298 (-6700 2250);
PAINT GREEN (-6700 2250);
FORCEPROP 2 LAST ATTRIBUTE 1UF
J 0
(-6700 2400);
DISPLAY 0.638298 (-6700 2400);
PAINT GREEN (-6700 2400);
FORCEPROP 0 LASTPIN (-6550 2150) $PN 2
J 2
(-6515 2165);
DISPLAY 0.808511 (-6515 2165);
PAINT MONO (-6515 2165);
FORCEPROP 0 LASTPIN (-6700 2150) $PN 1
J 0
(-6710 2165);
DISPLAY 0.808511 (-6710 2165);
PAINT MONO (-6710 2165);
FORCEPROP 1 LAST VALUE SC1U16V3KX-2GP
J 0
(-6700 2450);
DISPLAY 0.617021 (-6700 2450);
PAINT GREEN (-6700 2450);
FORCEPROP 2 LAST TOLERANCE 10%
J 0
(-6700 2300);
DISPLAY 0.638298 (-6700 2300);
PAINT GREEN (-6700 2300);
FORCEPROP 2 LAST CDS_LIB w_hdl
R 1
J 0
(-6625 2150);
PAINT MONO (-6625 2150);
DISPLAY INVISIBLE (-6625 2150);
FORCEPROP 1 LAST CDS_LMAN_SYM_OUTLINE -50,25,50,-25
R 1
J 0
(-6625 2150);
DISPLAY 0.468085 (-6625 2150);
PAINT GREEN (-6625 2150);
DISPLAY INVISIBLE (-6625 2150);
FORCEPROP 1 LAST PART_NUMBER 78.10521.5BL
R 1
J 0
(-6625 2150);
DISPLAY 0.617021 (-6625 2150);
PAINT GREEN (-6625 2150);
DISPLAY INVISIBLE (-6625 2150);
FORCEPROP 1 LAST PACK_TYPE SMD-BCG
R 1
J 0
(-6625 2150);
DISPLAY 0.617021 (-6625 2150);
PAINT GREEN (-6625 2150);
DISPLAY INVISIBLE (-6625 2150);
FORCEPROP 0 LAST $SEC 1
R 1
J 0
(-6625 2175);
PAINT MONO (-6625 2175);
DISPLAY INVISIBLE (-6625 2175);
FORCEPROP 0 LAST CDS_SEC 1
R 1
J 0
(-6625 2175);
PAINT MONO (-6625 2175);
DISPLAY INVISIBLE (-6625 2175);
FORCEPROP 1 LAST PATH I52
R 1
J 0
(-6625 2150);
DISPLAY 0.617021 (-6625 2150);
PAINT GREEN (-6625 2150);
DISPLAY INVISIBLE (-6625 2150);
FORCEPROP 0 LAST CDS_LOCATION C8W1
R 1
J 0
(-6625 2175);
PAINT MONO (-6625 2175);
DISPLAY INVISIBLE (-6625 2175);
FORCEADD DIODE..1
R 6
(-7050 2150);
FORCEPROP 1 LASTPIN (-6950 2150) $PN 1
J 0
(-6985 2111);
DISPLAY 0.617021 (-6985 2111);
PAINT AQUA (-6985 2111);
FORCEPROP 1 LASTPIN (-7150 2150) $PN 2
J 2
(-7115 2111);
DISPLAY 0.617021 (-7115 2111);
PAINT AQUA (-7115 2111);
FORCEPROP 1 LAST PACK_TYPE SMLF
J 0
(-7150 1961);
DISPLAY 0.617021 (-7150 1961);
PAINT SKYBLUE (-7150 1961);
FORCEPROP 1 LAST MATERIAL IC
J 0
(-7150 1999);
DISPLAY 0.617021 (-7150 1999);
PAINT SKYBLUE (-7150 1999);
FORCEPROP 1 LAST VALUE BAT54WS
J 0
(-7150 2046);
DISPLAY 0.617021 (-7150 2046);
PAINT SKYBLUE (-7150 2046);
FORCEPROP 1 LAST PART_NUMBER C73510-001
J 0
(-7150 2221);
DISPLAY 0.617021 (-7150 2221);
PAINT BLUE (-7150 2221);
FORCEPROP 1 LAST LOCATION CR3W1
J 0
(-7152 2265);
DISPLAY 0.617021 (-7152 2265);
PAINT AQUA (-7152 2265);
FORCEPROP 2 LAST CDS_LIB mstr_discrete
J 0
(-7050 2103);
PAINT ORANGE (-7050 2103);
DISPLAY INVISIBLE (-7050 2103);
FORCEPROP 2 LAST SEC_TYPE SMLF
J 2
(-7075 1827);
DISPLAY 1.021277 (-7075 1827);
PAINT ORANGE (-7075 1827);
DISPLAY INVISIBLE (-7075 1827);
FORCEPROP 2 LAST SEC 1
J 2
(-7075 1843);
DISPLAY 0.680851 (-7075 1843);
PAINT MONO (-7075 1843);
DISPLAY INVISIBLE (-7075 1843);
FORCEPROP 1 LAST PATH I55
J 0
(-7070 1940);
DISPLAY 0.978723 (-7070 1940);
PAINT PINK (-7070 1940);
DISPLAY INVISIBLE (-7070 1940);
FORCEPROP 2 LAST CDS_LOCATION CR3W1
J 0
(-7077 1965);
DISPLAY 0.617021 (-7077 1965);
PAINT AQUA (-7077 1965);
DISPLAY INVISIBLE (-7077 1965);
FORCEADD RES..2
(-6350 1950);
FORCEPROP 1 LAST TOLERANCE 1%
J 0
(-6305 1975);
DISPLAY 0.617021 (-6305 1975);
PAINT SKYBLUE (-6305 1975);
FORCEPROP 1 LAST PACK_TYPE 0402
J 0
(-6310 1775);
DISPLAY 0.617021 (-6310 1775);
PAINT SKYBLUE (-6310 1775);
FORCEPROP 1 LAST PART_NUMBER G21796-010
J 0
(-6310 1825);
DISPLAY 0.617021 (-6310 1825);
PAINT BLUE (-6310 1825);
FORCEPROP 1 LAST MATERIAL CHIP
J 0
(-6310 1875);
DISPLAY 0.617021 (-6310 1875);
PAINT SKYBLUE (-6310 1875);
FORCEPROP 1 LAST WATTAGE 1/16W
J 0
(-6310 1925);
DISPLAY 0.617021 (-6310 1925);
PAINT SKYBLUE (-6310 1925);
FORCEPROP 1 LAST VALUE 100.0K
J 0
(-6305 2025);
DISPLAY 0.617021 (-6305 2025);
PAINT SKYBLUE (-6305 2025);
FORCEPROP 1 LAST LOCATION R3W2
J 0
(-6305 2075);
DISPLAY 0.617021 (-6305 2075);
PAINT AQUA (-6305 2075);
FORCEPROP 1 LAST PATH I56
J 0
(-6300 2125);
DISPLAY 0.978723 (-6300 2125);
PAINT WHITE (-6300 2125);
DISPLAY INVISIBLE (-6300 2125);
FORCEPROP 2 LAST CDS_SEC 1
J 0
(-6300 2175);
PAINT MONO (-6300 2175);
DISPLAY INVISIBLE (-6300 2175);
FORCEPROP 0 LAST ROOM SB
J 0
(-6300 2175);
DISPLAY 1.021277 (-6300 2175);
PAINT ORANGE (-6300 2175);
DISPLAY INVISIBLE (-6300 2175);
FORCEPROP 2 LAST $SEC 1
J 0
(-6300 2175);
PAINT MONO (-6300 2175);
DISPLAY INVISIBLE (-6300 2175);
FORCEPROP 2 LAST CDS_LIB mstr_discrete
J 0
(-6350 1950);
PAINT ORANGE (-6350 1950);
DISPLAY INVISIBLE (-6350 1950);
FORCEPROP 1 LASTPIN (-6350 2050) $PN 1
J 0
(-6345 2012);
DISPLAY 0.787234 (-6345 2012);
PAINT ORANGE (-6345 2012);
DISPLAY INVISIBLE (-6345 2012);
FORCEPROP 1 LASTPIN (-6350 1850) $PN 2
J 0
(-6345 1860);
DISPLAY 0.787234 (-6345 1860);
PAINT ORANGE (-6345 1860);
DISPLAY INVISIBLE (-6345 1860);
FORCEPROP 2 LAST CDS_LOCATION R3W2
J 0
(-6305 2075);
DISPLAY 0.617021 (-6305 2075);
PAINT AQUA (-6305 2075);
DISPLAY INVISIBLE (-6305 2075);
FORCEADD CAP_A..1
(-5950 1950);
FORCEPROP 1 LAST PART_NUMBER A36096-030
J 0
(-5900 1825);
DISPLAY 0.617021 (-5900 1825);
PAINT BLUE (-5900 1825);
FORCEPROP 1 LAST MATERIAL X7R
J 0
(-5900 1875);
DISPLAY 0.617021 (-5900 1875);
PAINT SKYBLUE (-5900 1875);
FORCEPROP 1 LAST PACK_TYPE 0402V
J 0
(-5900 1775);
DISPLAY 0.617021 (-5900 1775);
PAINT SKYBLUE (-5900 1775);
FORCEPROP 1 LASTPIN (-5950 1850) $PN 2
J 0
(-5940 1830);
DISPLAY 0.617021 (-5940 1830);
PAINT MONO (-5940 1830);
FORCEPROP 1 LASTPIN (-5950 2050) $PN 1
J 0
(-5940 2030);
DISPLAY 0.617021 (-5940 2030);
PAINT MONO (-5940 2030);
FORCEPROP 1 LAST LOCATION C3W2
J 0
(-5900 2075);
DISPLAY 0.617021 (-5900 2075);
PAINT AQUA (-5900 2075);
FORCEPROP 1 LAST VALUE 0.1UF
J 0
(-5900 2025);
DISPLAY 0.617021 (-5900 2025);
PAINT SKYBLUE (-5900 2025);
FORCEPROP 1 LAST VOLTAGE 16V
J 0
(-5900 1975);
DISPLAY 0.617021 (-5900 1975);
PAINT SKYBLUE (-5900 1975);
FORCEPROP 1 LAST TOLERANCE 10%
J 0
(-5900 1925);
DISPLAY 0.617021 (-5900 1925);
PAINT SKYBLUE (-5900 1925);
FORCEPROP 2 LAST SEC 1
J 0
(-5900 2150);
DISPLAY 0.936170 (-5900 2150);
PAINT MONO (-5900 2150);
DISPLAY INVISIBLE (-5900 2150);
FORCEPROP 2 LAST SEC_TYPE 0402V
J 0
(-5900 2150);
PAINT MONO (-5900 2150);
DISPLAY INVISIBLE (-5900 2150);
FORCEPROP 2 LAST CDS_SEC 1
J 0
(-5900 2100);
PAINT ORANGE (-5900 2100);
DISPLAY INVISIBLE (-5900 2100);
FORCEPROP 2 LAST CDS_LIB dev_discrete
J 0
(-5950 1950);
PAINT ORANGE (-5950 1950);
DISPLAY INVISIBLE (-5950 1950);
FORCEPROP 2 LAST BOM_COST PROC_SIDEBAND
J 0
(-5950 1950);
PAINT MONO (-5950 1950);
DISPLAY INVISIBLE (-5950 1950);
FORCEPROP 2 LAST ROOM PROC_SIDEBAND
J 0
(-5900 1700);
DISPLAY 0.978723 (-5900 1700);
PAINT ORANGE (-5900 1700);
DISPLAY INVISIBLE (-5900 1700);
FORCEPROP 1 LAST PATH I57
J 0
(-5900 2100);
DISPLAY 0.978723 (-5900 2100);
PAINT WHITE (-5900 2100);
DISPLAY INVISIBLE (-5900 2100);
FORCEPROP 2 LAST CDS_LOCATION C3W2
J 0
(-5900 2050);
DISPLAY 0.617021 (-5900 2050);
PAINT AQUA (-5900 2050);
DISPLAY INVISIBLE (-5900 2050);
FORCEADD RES..2
(-3200 4350);
FORCEPROP 1 LAST LOCATION R3W5
J 0
(-3105 4450);
DISPLAY 0.617021 (-3105 4450);
PAINT AQUA (-3105 4450);
FORCEPROP 1 LASTPIN (-3200 4450) $PN 1
J 0
(-3195 4412);
DISPLAY 0.617021 (-3195 4412);
PAINT ORANGE (-3195 4412);
FORCEPROP 1 LASTPIN (-3200 4250) $PN 2
J 0
(-3195 4260);
DISPLAY 0.617021 (-3195 4260);
PAINT ORANGE (-3195 4260);
FORCEPROP 1 LAST VALUE 10.0K
J 0
(-3105 4400);
DISPLAY 0.617021 (-3105 4400);
PAINT SKYBLUE (-3105 4400);
FORCEPROP 1 LAST TOLERANCE 1%
J 0
(-3105 4350);
DISPLAY 0.617021 (-3105 4350);
PAINT SKYBLUE (-3105 4350);
FORCEPROP 1 LAST PART_NUMBER G21796-016
R 1
J 0
(-3135 4225);
DISPLAY 0.617021 (-3135 4225);
PAINT BLUE (-3135 4225);
FORCEPROP 1 LAST WATTAGE 1/16W
J 0
(-3110 4300);
DISPLAY 0.617021 (-3110 4300);
PAINT SKYBLUE (-3110 4300);
FORCEPROP 1 LAST PACK_TYPE 0402
J 0
(-3110 4200);
DISPLAY 0.617021 (-3110 4200);
PAINT SKYBLUE (-3110 4200);
FORCEPROP 1 LAST MATERIAL CHIP
J 0
(-3110 4250);
DISPLAY 0.617021 (-3110 4250);
PAINT SKYBLUE (-3110 4250);
FORCEPROP 2 LAST ROOM CPU0
J 0
(-3175 4125);
PAINT WHITE (-3175 4125);
DISPLAY INVISIBLE (-3175 4125);
FORCEPROP 2 LAST BOM_COST PROC_SIDEBAND
J 0
(-3200 4350);
PAINT WHITE (-3200 4350);
DISPLAY INVISIBLE (-3200 4350);
FORCEPROP 2 LAST CDS_LIB mstr_discrete
J 2
(-3200 4350);
PAINT ORANGE (-3200 4350);
DISPLAY INVISIBLE (-3200 4350);
FORCEPROP 2 LAST SEC_TYPE 0402
J 0
(-3150 4575);
DISPLAY 1.021277 (-3150 4575);
PAINT ORANGE (-3150 4575);
DISPLAY INVISIBLE (-3150 4575);
FORCEPROP 2 LAST SEC 1
J 0
(-3150 4575);
DISPLAY 0.680851 (-3150 4575);
PAINT MONO (-3150 4575);
DISPLAY INVISIBLE (-3150 4575);
FORCEPROP 1 LAST PATH I58
J 0
(-3150 4525);
DISPLAY 0.978723 (-3150 4525);
PAINT WHITE (-3150 4525);
DISPLAY INVISIBLE (-3150 4525);
FORCEPROP 2 LAST CDS_LOCATION R3W5
J 0
(-3155 4475);
DISPLAY 0.617021 (-3155 4475);
PAINT AQUA (-3155 4475);
DISPLAY INVISIBLE (-3155 4475);
FORCEADD GND..1
(-3325 1975);
FORCEPROP 3 LASTPIN (-3325 2025) SIG_NAME GND\g
J 0
(-3315 2035);
DISPLAY 0.659574 (-3315 2035);
PAINT MONO (-3315 2035);
DISPLAY INVISIBLE (-3315 2035);
FORCEPROP 2 LAST CDS_LIB mstr_symbols
J 0
(-3325 1975);
PAINT MONO (-3325 1975);
DISPLAY INVISIBLE (-3325 1975);
FORCEPROP 1 LAST HDL_POWER GND
J 0
(-3325 2125);
DISPLAY 0.872340 (-3325 2125);
PAINT GREEN (-3325 2125);
DISPLAY INVISIBLE (-3325 2125);
FORCEPROP 1 LAST SIZE 1B
J 0
(-3250 1925);
DISPLAY 0.872340 (-3250 1925);
PAINT AQUA (-3250 1925);
DISPLAY INVISIBLE (-3250 1925);
FORCEPROP 1 LAST BODY_TYPE PLUMBING
J 0
(-3370 1932);
DISPLAY 0.340426 (-3370 1932);
PAINT GREEN (-3370 1932);
DISPLAY INVISIBLE (-3370 1932);
FORCEPROP 1 LAST VOLTAGE 0.0V
J 0
(-3370 1932);
DISPLAY 0.340426 (-3370 1932);
PAINT GREEN (-3370 1932);
DISPLAY INVISIBLE (-3370 1932);
FORCEPROP 1 LAST PATH I6
J 0
(-3250 1975);
DISPLAY 0.872340 (-3250 1975);
PAINT AQUA (-3250 1975);
DISPLAY INVISIBLE (-3250 1975);
FORCEADD RES..2
(-3325 2300);
FORCEPROP 1 LAST VALUE 10.0K
J 0
(-3280 2375);
DISPLAY 0.617021 (-3280 2375);
PAINT SKYBLUE (-3280 2375);
FORCEPROP 1 LAST LOCATION R3W9
J 0
(-3280 2425);
DISPLAY 0.617021 (-3280 2425);
PAINT AQUA (-3280 2425);
FORCEPROP 1 LAST TOLERANCE 1%
J 0
(-3280 2325);
DISPLAY 0.617021 (-3280 2325);
PAINT SKYBLUE (-3280 2325);
FORCEPROP 1 LAST PACK_TYPE 0402
J 0
(-3285 2125);
DISPLAY 0.617021 (-3285 2125);
PAINT SKYBLUE (-3285 2125);
FORCEPROP 1 LASTPIN (-3325 2400) $PN 1
J 0
(-3320 2362);
DISPLAY 0.787234 (-3320 2362);
PAINT ORANGE (-3320 2362);
FORCEPROP 1 LAST WATTAGE 1/16W
J 0
(-3285 2275);
DISPLAY 0.617021 (-3285 2275);
PAINT SKYBLUE (-3285 2275);
FORCEPROP 1 LAST PART_NUMBER G21796-016
J 0
(-3285 2175);
DISPLAY 0.617021 (-3285 2175);
PAINT BLUE (-3285 2175);
FORCEPROP 1 LAST MATERIAL CHIP
J 0
(-3285 2225);
DISPLAY 0.617021 (-3285 2225);
PAINT SKYBLUE (-3285 2225);
FORCEPROP 1 LASTPIN (-3325 2200) $PN 2
J 0
(-3320 2210);
DISPLAY 0.787234 (-3320 2210);
PAINT ORANGE (-3320 2210);
FORCEPROP 2 LAST CDS_LIB mstr_discrete
J 0
(-3325 2300);
PAINT MONO (-3325 2300);
DISPLAY INVISIBLE (-3325 2300);
FORCEPROP 0 LAST BOM_COST ST_FLASH
J 0
(-3275 2625);
DISPLAY 1.021277 (-3275 2625);
PAINT ORANGE (-3275 2625);
DISPLAY INVISIBLE (-3275 2625);
FORCEPROP 0 LAST ROOM M_2
J 0
(-3275 2525);
DISPLAY 1.021277 (-3275 2525);
PAINT ORANGE (-3275 2525);
DISPLAY INVISIBLE (-3275 2525);
FORCEPROP 1 LAST PATH I7
J 0
(-3275 2475);
DISPLAY 0.978723 (-3275 2475);
PAINT WHITE (-3275 2475);
DISPLAY INVISIBLE (-3275 2475);
FORCEPROP 0 LAST SEC 1
J 0
(-3275 2475);
DISPLAY 0.680851 (-3275 2475);
PAINT MONO (-3275 2475);
DISPLAY INVISIBLE (-3275 2475);
FORCEPROP 2 LAST SEC_TYPE 0402
J 0
(-3275 2525);
DISPLAY 1.021277 (-3275 2525);
PAINT ORANGE (-3275 2525);
DISPLAY INVISIBLE (-3275 2525);
FORCEADD RES..2
R 2
(-3325 2775);
FORCEPROP 1 LAST PART_NUMBER G21796-072
J 2
(-3365 2650);
DISPLAY 0.617021 (-3365 2650);
PAINT BLUE (-3365 2650);
FORCEPROP 1 LAST WATTAGE 1/16W
J 2
(-3365 2700);
DISPLAY 0.617021 (-3365 2700);
PAINT SKYBLUE (-3365 2700);
FORCEPROP 1 LAST LOCATION R3W7
J 2
(-3370 2900);
DISPLAY 0.617021 (-3370 2900);
PAINT AQUA (-3370 2900);
FORCEPROP 1 LAST TOLERANCE 1%
J 2
(-3370 2750);
DISPLAY 0.617021 (-3370 2750);
PAINT SKYBLUE (-3370 2750);
FORCEPROP 1 LASTPIN (-3325 2675) $PN 2
J 2
(-3330 2685);
DISPLAY 0.787234 (-3330 2685);
PAINT ORANGE (-3330 2685);
FORCEPROP 1 LAST MATERIAL CHIP
J 2
(-3365 2800);
DISPLAY 0.617021 (-3365 2800);
PAINT SKYBLUE (-3365 2800);
FORCEPROP 1 LASTPIN (-3325 2875) $PN 1
J 2
(-3330 2837);
DISPLAY 0.787234 (-3330 2837);
PAINT ORANGE (-3330 2837);
FORCEPROP 1 LAST VALUE 4.75K
J 2
(-3370 2850);
DISPLAY 0.617021 (-3370 2850);
PAINT SKYBLUE (-3370 2850);
FORCEPROP 1 LAST PACK_TYPE 0402
J 2
(-3365 2600);
DISPLAY 0.617021 (-3365 2600);
PAINT SKYBLUE (-3365 2600);
FORCEPROP 2 LAST ROOM SB_SPI
J 0
(-3350 2950);
DISPLAY 1.021277 (-3350 2950);
PAINT ORANGE (-3350 2950);
DISPLAY INVISIBLE (-3350 2950);
FORCEPROP 2 LAST BOM_COST MIO_BIOS_MEM
J 0
(-3350 3000);
DISPLAY 1.021277 (-3350 3000);
PAINT ORANGE (-3350 3000);
DISPLAY INVISIBLE (-3350 3000);
FORCEPROP 2 LAST NO_XNET_CONNECTION 1
J 0
(-3375 3000);
PAINT MONO (-3375 3000);
DISPLAY INVISIBLE (-3375 3000);
FORCEPROP 2 LAST CDS_LIB mstr_discrete
J 0
(-3325 2775);
PAINT MONO (-3325 2775);
DISPLAY INVISIBLE (-3325 2775);
FORCEPROP 1 LAST PATH I8
J 2
(-3375 2950);
DISPLAY 0.978723 (-3375 2950);
PAINT WHITE (-3375 2950);
DISPLAY INVISIBLE (-3375 2950);
FORCEPROP 0 LAST SEC 1
J 0
(-3350 2950);
DISPLAY 0.680851 (-3350 2950);
PAINT MONO (-3350 2950);
DISPLAY INVISIBLE (-3350 2950);
FORCEPROP 2 LAST SEC_TYPE 0402
J 0
(-3375 3000);
DISPLAY 1.021277 (-3375 3000);
PAINT ORANGE (-3375 3000);
DISPLAY INVISIBLE (-3375 3000);
FORCEADD P3V3_STBY..1
(-3325 3100);
FORCEPROP 3 LASTPIN (-3325 3050) SIG_NAME P3V3_STBY\g
J 0
(-3315 3060);
DISPLAY 0.659574 (-3315 3060);
PAINT MONO (-3315 3060);
DISPLAY INVISIBLE (-3315 3060);
FORCEPROP 1 LAST HDL_POWER P3V3_STBY
J 0
(-3625 2975);
DISPLAY 0.872340 (-3625 2975);
PAINT ORANGE (-3625 2975);
DISPLAY INVISIBLE (-3625 2975);
FORCEPROP 1 LAST BODY_TYPE PLUMBING
J 0
(-3370 3057);
DISPLAY 0.340426 (-3370 3057);
PAINT GREEN (-3370 3057);
DISPLAY INVISIBLE (-3370 3057);
FORCEPROP 1 LAST SIZE 1B
J 0
(-3280 3122);
DISPLAY 0.340426 (-3280 3122);
PAINT GREEN (-3280 3122);
DISPLAY INVISIBLE (-3280 3122);
FORCEPROP 2 LAST CDS_LIB mstr_symbols
J 0
(-3325 3100);
PAINT MONO (-3325 3100);
DISPLAY INVISIBLE (-3325 3100);
FORCEPROP 1 LAST VOLTAGE 3.3V
J 0
(-3370 3057);
DISPLAY 0.340426 (-3370 3057);
PAINT GREEN (-3370 3057);
DISPLAY INVISIBLE (-3370 3057);
FORCEPROP 1 LAST PATH I9
J 0
(-3280 3102);
DISPLAY 0.340426 (-3280 3102);
PAINT GREEN (-3280 3102);
DISPLAY INVISIBLE (-3280 3102);
FORCEADD DNS..2
(-4845 2870);
PAINT RED (-4845 2870);
FORCEPROP 2 LAST CDS_LIB mstr_misc
J 0
(-4845 2870);
PAINT MONO (-4845 2870);
DISPLAY INVISIBLE (-4845 2870);
FORCEPROP 1 LAST COMMENT_BODY TRUE
R 1
J 0
(-4770 2645);
DISPLAY 0.872340 (-4770 2645);
PAINT GREEN (-4770 2645);
DISPLAY INVISIBLE (-4770 2645);
FORCEADD INTEL_CORP_BPAGE..1
(0 0);
FORCEPROP 1 LAST CDS_CON_LAST_MODIFIED Fri Jun 16 17:49:30 2017
J 0
(-1425 325);
PAINT ORANGE (-1425 325);
DISPLAY INVISIBLE (-1425 325);
FORCEPROP 2 LAST CUSTOM_TXT_CDS <XR_PAGE_TITLE>
J 0
(-7890 5250);
DISPLAY 0.638298 (-7890 5250);
PAINT PINK (-7890 5250);
DISPLAY INVISIBLE (-7890 5250);
FORCEPROP 2 LAST CUSTOM_TXT_CDS <CON_LAST_MODIFIED>
J 0
(-4000 100);
PAINT ORANGE (-4000 100);
FORCEPROP 2 LAST CUSTOM_TXT_CDS <CURRENT_DESIGN_SHEET> OF <TOTAL_DESIGN_SHEETS>
J 0
(-500 25);
PAINT ORANGE (-500 25);
FORCEPROP 1 LAST SCH_TITLE TPM PRESENT AND RESET CIRCUIT
J 0
(-7950 50);
DISPLAY 2.468085 (-7950 50);
PAINT ORANGE (-7950 50);
FORCEPROP 1 LAST COMMENT_BODY TRUE
J 0
(12 12);
DISPLAY 0.468085 (12 12);
PAINT GREEN (12 12);
DISPLAY INVISIBLE (12 12);
FORCEPROP 2 LAST CDS_LIB mstr_symbols
J 0
(0 0);
PAINT MONO (0 0);
DISPLAY INVISIBLE (0 0);
FORCEPROP 2 LAST PAGE_BORDER TRUE
J 0
(-7890 5250);
DISPLAY 0.638298 (-7890 5250);
PAINT PINK (-7890 5250);
DISPLAY INVISIBLE (-7890 5250);
FORCEPROP 2 LAST CDS_XR_PAGE_TITLE CR-249 : @BASEBOARD_FAB2_LIB.BASEBOARD_FAB2(SCH_1):PAGE249
J 0
(-7890 5250);
DISPLAY 0.638298 (-7890 5250);
PAINT PINK (-7890 5250);
DISPLAY INVISIBLE (-7890 5250);
WIRE 16 -1 (-3200 3750)(-3200 3650);
WIRE 16 -1 (-4850 1750)(-4850 1725);
WIRE 16 -1 (-4850 1750)(-5950 1750);
WIRE 16 -1 (-4850 2050)(-4850 1750);
WIRE 16 -1 (-6350 1750)(-5950 1750);
WIRE 16 -1 (-5950 1850)(-5950 1750);
WIRE 16 -1 (-6350 1850)(-6350 1750);
WIRE 16 -1 (-2350 2300)(-2350 2200);
WIRE 16 -1 (-4850 2950)(-4850 3000);
WIRE 16 -1 (-2050 2900)(-2050 2850);
WIRE 16 -1 (-3200 4750)(-3200 4700);
WIRE 16 -1 (-3200 4700)(-2300 4700);
WIRE 16 -1 (-3200 4450)(-3200 4700);
WIRE 16 -1 (-2300 4700)(-2300 4550);
WIRE 16 -1 (-6850 1850)(-6850 1750);
WIRE 16 -1 (-2050 3150)(-2050 3200);
WIRE 16 -1 (-2350 3150)(-2050 3150);
WIRE 16 -1 (-2050 3100)(-2050 3150);
WIRE 16 -1 (-2350 2800)(-2350 3150);
WIRE 16 -1 (-2300 4000)(-2300 3900);
WIRE 16 -1 (-3325 2200)(-3325 2025);
WIRE 16 -1 (-3325 2875)(-3325 3050);
WIRE 16 -1 (-4850 2450)(-4850 2600);
WIRE 16 -1 (-4850 2600)(-4850 2750);
WIRE 16 -1 (-4550 3850)(-6100 3850);
FORCEPROP 2 LAST SIG_NAME FM_TPM_PRES_RST_N
J 0
(-6035 3860);
DISPLAY 0.680851 (-6035 3860);
PAINT ORANGE (-6035 3860);
WIRE 16 -1 (-4450 3850)(-4550 3850);
WIRE 16 -1 (-4550 2600)(-4850 2600);
WIRE 16 -1 (-6050 3350)(-4550 3350);
WIRE 16 -1 (-4550 2600)(-4550 3350);
WIRE 16 -1 (-4550 3850)(-4550 3350);
WIRE 16 -1 (-2900 2600)(-2550 2600);
WIRE 16 -1 (-2900 3350)(-4550 3350);
WIRE 16 -1 (-2900 3350)(-2900 2600);
WIRE 3 682 (-2650 3800)(-1200 3800);
WIRE 3 682 (-2650 4750)(-2650 3800);
WIRE 3 682 (-1200 3800)(-1200 4750);
WIRE 3 682 (-1200 4750)(-2650 4750);
WIRE 3 2175 (-2550 2700)(-1700 2700);
WIRE 3 2175 (-1700 3350)(-1700 2700);
WIRE 3 2175 (-2550 3350)(-2550 2700);
WIRE 3 2175 (-2550 3350)(-1700 3350);
WIRE 16 -1 (-3325 2400)(-3325 2500);
WIRE 16 -1 (-3325 2500)(-3325 2675);
WIRE 16 -1 (-3325 2500)(-2550 2500);
FORCEPROP 2 LAST SIG_NAME VREF_2V2
J 0
(-3160 2510);
DISPLAY 0.680851 (-3160 2510);
PAINT ORANGE (-3160 2510);
FORCEPROP 2 LASTPROP $XRERR UNIQUE?
J 0
(-3400 2510);
DISPLAY 0.638298 (-3400 2510);
PAINT MONO (-3400 2510);
DISPLAY INVISIBLE (-3400 2510);
WIRE 16 -1 (-3200 3950)(-3200 4100);
WIRE 16 -1 (-3200 4250)(-3200 4100);
WIRE 16 -1 (-3200 4100)(-2450 4100);
FORCEPROP 2 LAST SIG_NAME FM_TPM_PRES_RST
J 0
(-3135 4110);
DISPLAY 0.680851 (-3135 4110);
PAINT ORANGE (-3135 4110);
FORCEPROP 2 LASTPROP $XRERR UNIQUE?
J 0
(-3375 4110);
DISPLAY 0.638298 (-3375 4110);
PAINT MONO (-3375 4110);
DISPLAY INVISIBLE (-3375 4110);
WIRE 3 682 (-2900 4500)(-3250 4500);
WIRE 3 682 (-2900 4200)(-2900 4500);
WIRE 3 682 (-3250 4500)(-3250 4200);
WIRE 3 682 (-3250 4200)(-2900 4200);
WIRE 16 -1 (-2300 4200)(-2300 4300);
WIRE 16 -1 (-2300 4300)(-2300 4350);
WIRE 16 -1 (-2300 4300)(-1600 4300);
FORCEPROP 2 LAST SIG_NAME RST_BMC_EXTRST_N
J 0
(-2135 4310);
DISPLAY 0.680851 (-2135 4310);
PAINT ORANGE (-2135 4310);
WIRE 16 -1 (-4200 3850)(-3350 3850);
FORCEPROP 2 LAST SIG_NAME FM_TPM_PRES_RST_N_R
J 0
(-4060 3860);
DISPLAY 0.680851 (-4060 3860);
PAINT ORANGE (-4060 3860);
FORCEPROP 2 LASTPROP $XRERR UNIQUE?
J 0
(-4300 3860);
DISPLAY 0.638298 (-4300 3860);
PAINT MONO (-4300 3860);
DISPLAY INVISIBLE (-4300 3860);
WIRE 3 2175 (-5100 2550)(-4500 2550);
WIRE 3 2175 (-4500 3150)(-4500 2550);
WIRE 3 2175 (-5100 3150)(-5100 2550);
WIRE 3 2175 (-5100 3150)(-4500 3150);
WIRE 3 682 (-6000 1700)(-5650 1700);
WIRE 3 682 (-6000 2200)(-6000 1700);
WIRE 3 682 (-5650 1700)(-5650 2200);
WIRE 3 682 (-5650 2200)(-6000 2200);
WIRE 3 682 (-6400 2200)(-6400 1700);
WIRE 3 682 (-6050 2200)(-6400 2200);
WIRE 3 682 (-6400 1700)(-6050 1700);
WIRE 3 682 (-6050 1700)(-6050 2200);
WIRE 16 -1 (-6350 2150)(-6550 2150);
WIRE 16 -1 (-6350 2050)(-6350 2150);
WIRE 16 -1 (-5950 2150)(-6350 2150);
WIRE 16 -1 (-5950 2150)(-5950 2050);
WIRE 16 -1 (-5050 2150)(-5950 2150);
FORCEPROP 2 LAST SIG_NAME BMC_TPM_HW_C_RST
J 0
(-5585 2160);
DISPLAY 0.680851 (-5585 2160);
PAINT ORANGE (-5585 2160);
FORCEPROP 2 LASTPROP $XRERR UNIQUE?
J 0
(-5825 2160);
DISPLAY 0.638298 (-5825 2160);
PAINT MONO (-5825 2160);
DISPLAY INVISIBLE (-5825 2160);
WIRE 3 682 (-7200 1950)(-6900 1950);
WIRE 3 682 (-7200 2350)(-7200 1950);
WIRE 3 682 (-6900 1950)(-6900 2350);
WIRE 3 682 (-6900 2350)(-7200 2350);
WIRE 16 -1 (-6850 3350)(-6250 3350);
WIRE 16 -1 (-6950 2150)(-6850 2150);
WIRE 16 -1 (-6850 2050)(-6850 2150);
WIRE 16 -1 (-6700 2150)(-6850 2150);
WIRE 16 -1 (-6850 2150)(-6850 3350);
FORCEPROP 2 LAST SIG_NAME BMC_SELF_HW_D_RST
J 0
(-6835 3360);
DISPLAY 0.680851 (-6835 3360);
PAINT ORANGE (-6835 3360);
FORCEPROP 2 LASTPROP $XRERR UNIQUE?
J 0
(-7075 3360);
DISPLAY 0.638298 (-7075 3360);
PAINT MONO (-7075 3360);
DISPLAY INVISIBLE (-7075 3360);
WIRE 16 -1 (-7150 2150)(-7650 2150);
FORCEPROP 2 LAST SIG_NAME BMC_SELF_HW_RST
J 0
(-7635 2160);
DISPLAY 0.680851 (-7635 2160);
PAINT ORANGE (-7635 2160);
WIRE 3 2175 (-7850 1450)(-300 1450);
WIRE 3 2175 (-300 4900)(-300 1450);
WIRE 3 2175 (-7850 4900)(-7850 1450);
WIRE 3 2175 (-7850 4900)(-300 4900);
WIRE 16 -1 (-1450 2550)(-2050 2550);
FORCEPROP 2 LAST SIG_NAME FM_TPM_PRES_N
J 0
(-1985 2560);
DISPLAY 0.680851 (-1985 2560);
PAINT ORANGE (-1985 2560);
DOT 1 (-2300 4300);
DOT 1 (-2050 3150);
DOT 1 (-3200 4700);
DOT 1 (-3325 2500);
DOT 1 (-4850 2600);
DOT 1 (-4550 3850);
DOT 1 (-4550 3350);
DOT 1 (-4850 1750);
DOT 1 (-6350 2150);
DOT 1 (-6850 2150);
DOT 1 (-5950 1750);
DOT 1 (-5950 2150);
DOT 1 (-3200 4100);
FORCENOTE
TP FAB1 FOR BMC TPM 1120
(-7800 4800) 0;
DISPLAY LEFT (-7800 4800);
DISPLAY 1.021277 (-7800 4800);
PAINT RED (-7800 4800);
FORCENOTE
TP FAB3 CHANGE DIODE 0919
(-7500 1900) 0;
DISPLAY LEFT (-7500 1900);
DISPLAY 0.638298 (-7500 1900);
PAINT RED (-7500 1900);
FORCENOTE
TP FAB3 ADD CAP 0919
(-6000 1600) 0;
DISPLAY LEFT (-6000 1600);
DISPLAY 0.638298 (-6000 1600);
PAINT RED (-6000 1600);
FORCENOTE
TP FAB3 CHANGE RES 0919
(-6400 1650) 0;
DISPLAY LEFT (-6400 1650);
DISPLAY 0.638298 (-6400 1650);
PAINT RED (-6400 1650);
FORCENOTE
TP FAB1 NOPOP 1221
(-5100 3175) 0;
DISPLAY LEFT (-5100 3175);
DISPLAY 1.021277 (-5100 3175);
PAINT RED (-5100 3175);
FORCENOTE
TP FAB3 DEL SCHMITT BUFFER AND ADD BJT 0905
(-2650 4825) 0;
DISPLAY LEFT (-2650 4825);
DISPLAY 0.638298 (-2650 4825);
PAINT RED (-2650 4825);
FORCENOTE
TP FAB3 CHANGE RES 0919
(-3200 4600) 0;
DISPLAY LEFT (-3200 4600);
DISPLAY 0.638298 (-3200 4600);
PAINT RED (-3200 4600);
FORCENOTE
TP FAB3 CHANGE RES 0902
(-3200 4500) 0;
DISPLAY LEFT (-3200 4500);
DISPLAY 0.638298 (-3200 4500);
PAINT RED (-3200 4500);
FORCENOTE
TP FAB3 CHANGE RES 0905
(-3200 4550) 0;
DISPLAY LEFT (-3200 4550);
DISPLAY 0.638298 (-3200 4550);
PAINT RED (-3200 4550);
FORCENOTE
TP FAB3 ADD SCHMITT BUFFER 0831
(-2650 4775) 0;
DISPLAY LEFT (-2650 4775);
DISPLAY 0.638298 (-2650 4775);
PAINT RED (-2650 4775);
FORCENOTE
TP FAB1 CHANGE TO P5V_STBY 1221
(-2550 3375) 0;
DISPLAY LEFT (-2550 3375);
DISPLAY 0.638298 (-2550 3375);
PAINT RED (-2550 3375);
FORCENOTE
WITH TPM MODULE: V=1.64V
(-6150 4050) 0;
DISPLAY LEFT (-6150 4050);
DISPLAY 1.021277 (-6150 4050);
PAINT PURPLE (-6150 4050);
QUIT
